(kicad_pcb
	(version 20260206)
	(generator "pcbnew")
	(generator_version "10.0")
	(general
		(thickness 1.6)
		(legacy_teardrops no)
	)
	(paper "A4")
	(title_block
		(title "01162023_DA0F0TEBIF0_F0T_Expander_BD_F_brd_V02_OCP.brd")
		(comment 1 "Grand Teton / footprints 9693-9699 of 9728")
	)
	(layers
		(0 "F.Cu" signal "TOP")
		(4 "In1.Cu" signal "GND")
		(6 "In2.Cu" signal "VCC")
		(8 "In3.Cu" signal "VCC1")
		(10 "In4.Cu" signal "GND1")
		(12 "In5.Cu" signal "IN1")
		(14 "In6.Cu" signal "GND2")
		(16 "In7.Cu" signal "IN2")
		(18 "In8.Cu" signal "GND3")
		(20 "In9.Cu" signal "IN3")
		(22 "In10.Cu" signal "GND4")
		(24 "In11.Cu" signal "IN4")
		(26 "In12.Cu" signal "GND5")
		(28 "In13.Cu" signal "IN5")
		(30 "In14.Cu" signal "GND6")
		(32 "In15.Cu" signal "IN6")
		(34 "In16.Cu" signal "GND7")
		(2 "B.Cu" signal "BOTTOM")
		(9 "F.Adhes" user "F.Adhesive")
		(11 "B.Adhes" user "B.Adhesive")
		(13 "F.Paste" user "Package Geometry/Pastemask Top")
		(15 "B.Paste" user "Package Geometry/Pastemask Bottom")
		(5 "F.SilkS" user "Ref Des/Silkscreen Top")
		(7 "B.SilkS" user "Ref Des/Silkscreen Bottom")
		(1 "F.Mask" user "Board Geometry/Soldermask Top")
		(3 "B.Mask" user "Board Geometry/Soldermask Bottom")
		(17 "Dwgs.User" user "User.Drawings")
		(19 "Cmts.User" user "User.Comments")
		(21 "Eco1.User" user "User.Eco1")
		(23 "Eco2.User" user "User.Eco2")
		(25 "Edge.Cuts" user "Board Geometry/Outline")
		(27 "Margin" user)
		(31 "F.CrtYd" user "Package Geometry/Place Bound Top")
		(29 "B.CrtYd" user "Package Geometry/Place Bound Bottom")
		(35 "F.Fab" user "Ref Des/Assembly Top")
		(33 "B.Fab" user "Ref Des/Assembly Bottom")
	)
	(footprint ""
		(layer "B.Cu")
		(at 425.841922 -98.021648 180)
		(property "Reference" "R370"
			(at 0 0 0)
			(layer "B.SilkS")
			(hide yes)
			(effects
				(font
					(size 1.27 1.27)
				)
				(justify mirror)
			)
		)
		(property "Value" ""
			(at 0 0 0)
			(layer "B.Fab")
			(effects
				(font
					(size 1.27 1.27)
				)
				(justify mirror)
			)
		)
		(duplicate_pad_numbers_are_jumpers no)
		(fp_line
			(start 0.7874 0.4064)
			(end 0.7874 -0.4064)
			(stroke
				(width 0.1524)
				(type default)
			)
			(layer "B.SilkS")
		)
		(fp_line
			(start 0.7874 -0.4064)
			(end -0.7874 -0.4064)
			(stroke
				(width 0.1524)
				(type default)
			)
			(layer "B.SilkS")
		)
		(fp_line
			(start -0.7874 0.4064)
			(end 0.7874 0.4064)
			(stroke
				(width 0.1524)
				(type default)
			)
			(layer "B.SilkS")
		)
		(fp_line
			(start -0.7874 -0.4064)
			(end -0.7874 0.4064)
			(stroke
				(width 0.1524)
				(type default)
			)
			(layer "B.SilkS")
		)
		(fp_line
			(start 0.67945 0.3048)
			(end 0.67945 -0.305054)
			(stroke
				(width 0.1)
				(type default)
			)
			(layer "B.Fab")
		)
		(fp_line
			(start 0.67945 -0.305054)
			(end 0.12065 -0.305054)
			(stroke
				(width 0.1)
				(type default)
			)
			(layer "B.Fab")
		)
		(fp_line
			(start 0.12065 0.3048)
			(end 0.67945 0.3048)
			(stroke
				(width 0.1)
				(type default)
			)
			(layer "B.Fab")
		)
		(fp_line
			(start 0.12065 0.2794)
			(end 0.12065 0.3048)
			(stroke
				(width 0.1)
				(type default)
			)
			(layer "B.Fab")
		)
		(fp_line
			(start 0.12065 -0.2794)
			(end -0.12065 -0.2794)
			(stroke
				(width 0.1)
				(type default)
			)
			(layer "B.Fab")
		)
		(fp_line
			(start 0.12065 -0.305054)
			(end 0.12065 -0.2794)
			(stroke
				(width 0.1)
				(type default)
			)
			(layer "B.Fab")
		)
		(fp_line
			(start -0.120396 0.3048)
			(end -0.120396 0.2794)
			(stroke
				(width 0.1)
				(type default)
			)
			(layer "B.Fab")
		)
		(fp_line
			(start -0.120396 0.2794)
			(end 0.12065 0.2794)
			(stroke
				(width 0.1)
				(type default)
			)
			(layer "B.Fab")
		)
		(fp_line
			(start -0.12065 -0.2794)
			(end -0.12065 -0.3048)
			(stroke
				(width 0.1)
				(type default)
			)
			(layer "B.Fab")
		)
		(fp_line
			(start -0.12065 -0.3048)
			(end -0.67945 -0.3048)
			(stroke
				(width 0.1)
				(type default)
			)
			(layer "B.Fab")
		)
		(fp_line
			(start -0.67945 0.3048)
			(end -0.120396 0.3048)
			(stroke
				(width 0.1)
				(type default)
			)
			(layer "B.Fab")
		)
		(fp_line
			(start -0.67945 -0.3048)
			(end -0.67945 0.3048)
			(stroke
				(width 0.1)
				(type default)
			)
			(layer "B.Fab")
		)
		(pad "1" smd circle
			(at 0.40005 0)
			(size 0 0)
			(layers "B.Cu" "B.Mask" "B.Paste")
			(net "NIC7_DATA_OUT")
		)
		(pad "2" smd circle
			(at -0.40005 0)
			(size 0 0)
			(layers "B.Cu" "B.Mask" "B.Paste")
			(net "GND")
		)
	)
	(footprint ""
		(layer "B.Cu")
		(at 101.589586 -344.563954 90)
		(property "Reference" "R6370"
			(at 0 0 90)
			(layer "B.SilkS")
			(hide yes)
			(effects
				(font
					(size 1.27 1.27)
				)
				(justify mirror)
			)
		)
		(property "Value" ""
			(at 0 0 90)
			(layer "B.Fab")
			(effects
				(font
					(size 1.27 1.27)
				)
				(justify mirror)
			)
		)
		(duplicate_pad_numbers_are_jumpers no)
		(fp_line
			(start 0.7874 -0.4064)
			(end -0.7874 -0.4064)
			(stroke
				(width 0.1524)
				(type default)
			)
			(layer "B.SilkS")
		)
		(fp_line
			(start -0.7874 -0.4064)
			(end -0.7874 0.4064)
			(stroke
				(width 0.1524)
				(type default)
			)
			(layer "B.SilkS")
		)
		(fp_line
			(start 0.7874 0.4064)
			(end 0.7874 -0.4064)
			(stroke
				(width 0.1524)
				(type default)
			)
			(layer "B.SilkS")
		)
		(fp_line
			(start -0.7874 0.4064)
			(end 0.7874 0.4064)
			(stroke
				(width 0.1524)
				(type default)
			)
			(layer "B.SilkS")
		)
		(fp_line
			(start 0.67945 -0.305054)
			(end 0.12065 -0.305054)
			(stroke
				(width 0.1)
				(type default)
			)
			(layer "B.Fab")
		)
		(fp_line
			(start 0.12065 -0.305054)
			(end 0.12065 -0.2794)
			(stroke
				(width 0.1)
				(type default)
			)
			(layer "B.Fab")
		)
		(fp_line
			(start -0.12065 -0.3048)
			(end -0.67945 -0.3048)
			(stroke
				(width 0.1)
				(type default)
			)
			(layer "B.Fab")
		)
		(fp_line
			(start -0.67945 -0.3048)
			(end -0.67945 0.3048)
			(stroke
				(width 0.1)
				(type default)
			)
			(layer "B.Fab")
		)
		(fp_line
			(start 0.12065 -0.2794)
			(end -0.12065 -0.2794)
			(stroke
				(width 0.1)
				(type default)
			)
			(layer "B.Fab")
		)
		(fp_line
			(start -0.12065 -0.2794)
			(end -0.12065 -0.3048)
			(stroke
				(width 0.1)
				(type default)
			)
			(layer "B.Fab")
		)
		(fp_line
			(start 0.12065 0.2794)
			(end 0.12065 0.3048)
			(stroke
				(width 0.1)
				(type default)
			)
			(layer "B.Fab")
		)
		(fp_line
			(start -0.120396 0.2794)
			(end 0.12065 0.2794)
			(stroke
				(width 0.1)
				(type default)
			)
			(layer "B.Fab")
		)
		(fp_line
			(start 0.67945 0.3048)
			(end 0.67945 -0.305054)
			(stroke
				(width 0.1)
				(type default)
			)
			(layer "B.Fab")
		)
		(fp_line
			(start 0.12065 0.3048)
			(end 0.67945 0.3048)
			(stroke
				(width 0.1)
				(type default)
			)
			(layer "B.Fab")
		)
		(fp_line
			(start -0.120396 0.3048)
			(end -0.120396 0.2794)
			(stroke
				(width 0.1)
				(type default)
			)
			(layer "B.Fab")
		)
		(fp_line
			(start -0.67945 0.3048)
			(end -0.120396 0.3048)
			(stroke
				(width 0.1)
				(type default)
			)
			(layer "B.Fab")
		)
		(pad "1" smd circle
			(at 0.40005 0 270)
			(size 0 0)
			(layers "B.Cu" "B.Mask" "B.Paste")
			(net "SMB_9ZXL0451E_S3_ADDR0")
		)
		(pad "2" smd circle
			(at -0.40005 0 270)
			(size 0 0)
			(layers "B.Cu" "B.Mask" "B.Paste")
			(net "P3V3")
		)
	)
	(footprint ""
		(layer "B.Cu")
		(at 222.999046 -143.094202 -90)
		(property "Reference" "R4187"
			(at 0 0 90)
			(layer "B.SilkS")
			(hide yes)
			(effects
				(font
					(size 1.27 1.27)
				)
				(justify mirror)
			)
		)
		(property "Value" ""
			(at 0 0 90)
			(layer "B.Fab")
			(effects
				(font
					(size 1.27 1.27)
				)
				(justify mirror)
			)
		)
		(duplicate_pad_numbers_are_jumpers no)
		(fp_line
			(start -1.2954 0.5842)
			(end 1.2954 0.5842)
			(stroke
				(width 0.1524)
				(type default)
			)
			(layer "B.SilkS")
		)
		(fp_line
			(start 1.2954 0.5842)
			(end 1.2954 -0.5842)
			(stroke
				(width 0.1524)
				(type default)
			)
			(layer "B.SilkS")
		)
		(fp_line
			(start -1.2954 -0.5842)
			(end -1.2954 0.5842)
			(stroke
				(width 0.1524)
				(type default)
			)
			(layer "B.SilkS")
		)
		(fp_line
			(start 1.2954 -0.5842)
			(end -1.2954 -0.5842)
			(stroke
				(width 0.1524)
				(type default)
			)
			(layer "B.SilkS")
		)
		(fp_line
			(start -0.8636 0.4572)
			(end 0.8636 0.4572)
			(stroke
				(width 0.1)
				(type default)
			)
			(layer "B.Fab")
		)
		(fp_line
			(start 0.8636 0.4572)
			(end 0.8636 0.4318)
			(stroke
				(width 0.1)
				(type default)
			)
			(layer "B.Fab")
		)
		(fp_line
			(start 0.8636 0.4318)
			(end 0.8636 0.4064)
			(stroke
				(width 0.1)
				(type default)
			)
			(layer "B.Fab")
		)
		(fp_line
			(start -1.1938 0.4064)
			(end -0.8636 0.4064)
			(stroke
				(width 0.1)
				(type default)
			)
			(layer "B.Fab")
		)
		(fp_line
			(start -0.8636 0.4064)
			(end -0.8636 0.4572)
			(stroke
				(width 0.1)
				(type default)
			)
			(layer "B.Fab")
		)
		(fp_line
			(start 0.8636 0.4064)
			(end 1.1938 0.4064)
			(stroke
				(width 0.1)
				(type default)
			)
			(layer "B.Fab")
		)
		(fp_line
			(start 1.1938 0.4064)
			(end 1.1938 -0.406654)
			(stroke
				(width 0.1)
				(type default)
			)
			(layer "B.Fab")
		)
		(fp_line
			(start -1.1938 -0.406654)
			(end -1.1938 0.4064)
			(stroke
				(width 0.1)
				(type default)
			)
			(layer "B.Fab")
		)
		(fp_line
			(start -0.8636 -0.406654)
			(end -1.1938 -0.406654)
			(stroke
				(width 0.1)
				(type default)
			)
			(layer "B.Fab")
		)
		(fp_line
			(start 0.8636 -0.406654)
			(end 0.8636 -0.4572)
			(stroke
				(width 0.1)
				(type default)
			)
			(layer "B.Fab")
		)
		(fp_line
			(start 1.1938 -0.406654)
			(end 0.8636 -0.406654)
			(stroke
				(width 0.1)
				(type default)
			)
			(layer "B.Fab")
		)
		(fp_line
			(start -0.8636 -0.4572)
			(end -0.8636 -0.406654)
			(stroke
				(width 0.1)
				(type default)
			)
			(layer "B.Fab")
		)
		(fp_line
			(start 0.8636 -0.4572)
			(end -0.8636 -0.4572)
			(stroke
				(width 0.1)
				(type default)
			)
			(layer "B.Fab")
		)
		(pad "1" smd rect
			(at 0.7366 0 180)
			(size 0.7112 0.8128)
			(layers "B.Cu" "B.Mask" "B.Paste")
			(net "P3V3_CLK_GEN_VDDXTAL_CK440_PEX")
		)
		(pad "2" smd rect
			(at -0.7366 0 180)
			(size 0.7112 0.8128)
			(layers "B.Cu" "B.Mask" "B.Paste")
			(net "P3V3_CLK_GEN_VDDA25M_CK440_PEX")
		)
	)
	(footprint ""
		(layer "B.Cu")
		(at 177.423826 -192.270634 180)
		(property "Reference" "R1032"
			(at 0 0 0)
			(layer "B.SilkS")
			(hide yes)
			(effects
				(font
					(size 1.27 1.27)
				)
				(justify mirror)
			)
		)
		(property "Value" ""
			(at 0 0 0)
			(layer "B.Fab")
			(effects
				(font
					(size 1.27 1.27)
				)
				(justify mirror)
			)
		)
		(duplicate_pad_numbers_are_jumpers no)
		(fp_line
			(start 0.7874 0.4064)
			(end 0.7874 -0.4064)
			(stroke
				(width 0.1524)
				(type default)
			)
			(layer "B.SilkS")
		)
		(fp_line
			(start 0.7874 -0.4064)
			(end -0.7874 -0.4064)
			(stroke
				(width 0.1524)
				(type default)
			)
			(layer "B.SilkS")
		)
		(fp_line
			(start -0.7874 0.4064)
			(end 0.7874 0.4064)
			(stroke
				(width 0.1524)
				(type default)
			)
			(layer "B.SilkS")
		)
		(fp_line
			(start -0.7874 -0.4064)
			(end -0.7874 0.4064)
			(stroke
				(width 0.1524)
				(type default)
			)
			(layer "B.SilkS")
		)
		(fp_line
			(start 0.67945 0.3048)
			(end 0.67945 -0.305054)
			(stroke
				(width 0.1)
				(type default)
			)
			(layer "B.Fab")
		)
		(fp_line
			(start 0.67945 -0.305054)
			(end 0.12065 -0.305054)
			(stroke
				(width 0.1)
				(type default)
			)
			(layer "B.Fab")
		)
		(fp_line
			(start 0.12065 0.3048)
			(end 0.67945 0.3048)
			(stroke
				(width 0.1)
				(type default)
			)
			(layer "B.Fab")
		)
		(fp_line
			(start 0.12065 0.2794)
			(end 0.12065 0.3048)
			(stroke
				(width 0.1)
				(type default)
			)
			(layer "B.Fab")
		)
		(fp_line
			(start 0.12065 -0.2794)
			(end -0.12065 -0.2794)
			(stroke
				(width 0.1)
				(type default)
			)
			(layer "B.Fab")
		)
		(fp_line
			(start 0.12065 -0.305054)
			(end 0.12065 -0.2794)
			(stroke
				(width 0.1)
				(type default)
			)
			(layer "B.Fab")
		)
		(fp_line
			(start -0.120396 0.3048)
			(end -0.120396 0.2794)
			(stroke
				(width 0.1)
				(type default)
			)
			(layer "B.Fab")
		)
		(fp_line
			(start -0.120396 0.2794)
			(end 0.12065 0.2794)
			(stroke
				(width 0.1)
				(type default)
			)
			(layer "B.Fab")
		)
		(fp_line
			(start -0.12065 -0.2794)
			(end -0.12065 -0.3048)
			(stroke
				(width 0.1)
				(type default)
			)
			(layer "B.Fab")
		)
		(fp_line
			(start -0.12065 -0.3048)
			(end -0.67945 -0.3048)
			(stroke
				(width 0.1)
				(type default)
			)
			(layer "B.Fab")
		)
		(fp_line
			(start -0.67945 0.3048)
			(end -0.120396 0.3048)
			(stroke
				(width 0.1)
				(type default)
			)
			(layer "B.Fab")
		)
		(fp_line
			(start -0.67945 -0.3048)
			(end -0.67945 0.3048)
			(stroke
				(width 0.1)
				(type default)
			)
			(layer "B.Fab")
		)
		(pad "1" smd circle
			(at 0.40005 0)
			(size 0 0)
			(layers "B.Cu" "B.Mask" "B.Paste")
			(net "SPI_BIC1_MISO_LS01_DIR4")
		)
		(pad "2" smd circle
			(at -0.40005 0)
			(size 0 0)
			(layers "B.Cu" "B.Mask" "B.Paste")
			(net "P1V8_PEX")
		)
	)
	(footprint ""
		(layer "B.Cu")
		(at 180.975 -305.399948 -90)
		(property "Reference" "C3128"
			(at 0 0 90)
			(layer "B.SilkS")
			(hide yes)
			(effects
				(font
					(size 1.27 1.27)
				)
				(justify mirror)
			)
		)
		(property "Value" ""
			(at 0 0 90)
			(layer "B.Fab")
			(effects
				(font
					(size 1.27 1.27)
				)
				(justify mirror)
			)
		)
		(duplicate_pad_numbers_are_jumpers no)
		(fp_line
			(start -0.299974 0.150114)
			(end 0.299974 0.150114)
			(stroke
				(width 0.1)
				(type default)
			)
			(layer "B.Fab")
		)
		(fp_line
			(start 0.299974 0.150114)
			(end 0.299974 -0.150114)
			(stroke
				(width 0.1)
				(type default)
			)
			(layer "B.Fab")
		)
		(fp_line
			(start -0.299974 -0.150114)
			(end -0.299974 0.150114)
			(stroke
				(width 0.1)
				(type default)
			)
			(layer "B.Fab")
		)
		(fp_line
			(start 0.299974 -0.150114)
			(end -0.299974 -0.150114)
			(stroke
				(width 0.1)
				(type default)
			)
			(layer "B.Fab")
		)
		(pad "1" smd rect
			(at 0.2667 0 90)
			(size 0.3048 0.381)
			(layers "B.Cu" "B.Mask" "B.Paste")
			(net "P1V25_SERDES_VDDPLL_PEX1")
		)
		(pad "2" smd rect
			(at -0.2667 0 90)
			(size 0.3048 0.381)
			(layers "B.Cu" "B.Mask" "B.Paste")
			(net "GND")
		)
	)
	(footprint ""
		(layer "B.Cu")
		(at 327.414128 -219.80144 90)
		(property "Reference" "R4903"
			(at 0 0 90)
			(layer "B.SilkS")
			(hide yes)
			(effects
				(font
					(size 1.27 1.27)
				)
				(justify mirror)
			)
		)
		(property "Value" ""
			(at 0 0 90)
			(layer "B.Fab")
			(effects
				(font
					(size 1.27 1.27)
				)
				(justify mirror)
			)
		)
		(duplicate_pad_numbers_are_jumpers no)
		(fp_line
			(start 0.7874 -0.4064)
			(end -0.7874 -0.4064)
			(stroke
				(width 0.1524)
				(type default)
			)
			(layer "B.SilkS")
		)
		(fp_line
			(start -0.7874 -0.4064)
			(end -0.7874 0.4064)
			(stroke
				(width 0.1524)
				(type default)
			)
			(layer "B.SilkS")
		)
		(fp_line
			(start 0.7874 0.4064)
			(end 0.7874 -0.4064)
			(stroke
				(width 0.1524)
				(type default)
			)
			(layer "B.SilkS")
		)
		(fp_line
			(start -0.7874 0.4064)
			(end 0.7874 0.4064)
			(stroke
				(width 0.1524)
				(type default)
			)
			(layer "B.SilkS")
		)
		(fp_line
			(start 0.67945 -0.305054)
			(end 0.12065 -0.305054)
			(stroke
				(width 0.1)
				(type default)
			)
			(layer "B.Fab")
		)
		(fp_line
			(start 0.12065 -0.305054)
			(end 0.12065 -0.2794)
			(stroke
				(width 0.1)
				(type default)
			)
			(layer "B.Fab")
		)
		(fp_line
			(start -0.12065 -0.3048)
			(end -0.67945 -0.3048)
			(stroke
				(width 0.1)
				(type default)
			)
			(layer "B.Fab")
		)
		(fp_line
			(start -0.67945 -0.3048)
			(end -0.67945 0.3048)
			(stroke
				(width 0.1)
				(type default)
			)
			(layer "B.Fab")
		)
		(fp_line
			(start 0.12065 -0.2794)
			(end -0.12065 -0.2794)
			(stroke
				(width 0.1)
				(type default)
			)
			(layer "B.Fab")
		)
		(fp_line
			(start -0.12065 -0.2794)
			(end -0.12065 -0.3048)
			(stroke
				(width 0.1)
				(type default)
			)
			(layer "B.Fab")
		)
		(fp_line
			(start 0.12065 0.2794)
			(end 0.12065 0.3048)
			(stroke
				(width 0.1)
				(type default)
			)
			(layer "B.Fab")
		)
		(fp_line
			(start -0.120396 0.2794)
			(end 0.12065 0.2794)
			(stroke
				(width 0.1)
				(type default)
			)
			(layer "B.Fab")
		)
		(fp_line
			(start 0.67945 0.3048)
			(end 0.67945 -0.305054)
			(stroke
				(width 0.1)
				(type default)
			)
			(layer "B.Fab")
		)
		(fp_line
			(start 0.12065 0.3048)
			(end 0.67945 0.3048)
			(stroke
				(width 0.1)
				(type default)
			)
			(layer "B.Fab")
		)
		(fp_line
			(start -0.120396 0.3048)
			(end -0.120396 0.2794)
			(stroke
				(width 0.1)
				(type default)
			)
			(layer "B.Fab")
		)
		(fp_line
			(start -0.67945 0.3048)
			(end -0.120396 0.3048)
			(stroke
				(width 0.1)
				(type default)
			)
			(layer "B.Fab")
		)
		(pad "1" smd circle
			(at 0.40005 0 270)
			(size 0 0)
			(layers "B.Cu" "B.Mask" "B.Paste")
			(net "JTAG_FPGA_TMS")
		)
		(pad "2" smd circle
			(at -0.40005 0 270)
			(size 0 0)
			(layers "B.Cu" "B.Mask" "B.Paste")
			(net "P3V3_AUX")
		)
	)
	(footprint ""
		(layer "B.Cu")
		(at 113.693956 -137.56132 90)
		(property "Reference" "PC35"
			(at 0 0 90)
			(layer "B.SilkS")
			(hide yes)
			(effects
				(font
					(size 1.27 1.27)
				)
				(justify mirror)
			)
		)
		(property "Value" ""
			(at 0 0 90)
			(layer "B.Fab")
			(effects
				(font
					(size 1.27 1.27)
				)
				(justify mirror)
			)
		)
		(duplicate_pad_numbers_are_jumpers no)
		(fp_line
			(start 1.524 -0.762)
			(end -1.524 -0.762)
			(stroke
				(width 0.1524)
				(type default)
			)
			(layer "B.SilkS")
		)
		(fp_line
			(start -1.524 -0.762)
			(end -1.524 0.762)
			(stroke
				(width 0.1524)
				(type default)
			)
			(layer "B.SilkS")
		)
		(fp_line
			(start 1.524 0.762)
			(end 1.524 -0.762)
			(stroke
				(width 0.1524)
				(type default)
			)
			(layer "B.SilkS")
		)
		(fp_line
			(start -1.524 0.762)
			(end 1.524 0.762)
			(stroke
				(width 0.1524)
				(type default)
			)
			(layer "B.SilkS")
		)
		(fp_line
			(start 1.1049 -0.724916)
			(end 1.1049 0.724916)
			(stroke
				(width 0.1)
				(type default)
			)
			(layer "B.Fab")
		)
		(fp_line
			(start -1.1049 -0.724916)
			(end 1.1049 -0.724916)
			(stroke
				(width 0.1)
				(type default)
			)
			(layer "B.Fab")
		)
		(fp_line
			(start 1.1049 0.724916)
			(end -1.1049 0.724916)
			(stroke
				(width 0.1)
				(type default)
			)
			(layer "B.Fab")
		)
		(fp_line
			(start -1.1049 0.724916)
			(end -1.1049 -0.724916)
			(stroke
				(width 0.1)
				(type default)
			)
			(layer "B.Fab")
		)
		(pad "1" smd rect
			(at 0.889 0 90)
			(size 1.016 1.27)
			(layers "B.Cu" "B.Mask" "B.Paste")
			(net "P3V3_AUX")
		)
		(pad "2" smd rect
			(at -0.889 0 90)
			(size 1.016 1.27)
			(layers "B.Cu" "B.Mask" "B.Paste")
			(net "GND")
		)
	)
)
